(kicad_pcb
	(version 20260206)
	(generator "pcbnew")
	(generator_version "10.0")
	(general
		(thickness 1.6)
		(legacy_teardrops no)
	)
	(paper "A4")
	(title_block
		(title "01162023_DA0F0TEBIF0_F0T_Expander_BD_F_brd_V02_OCP.brd")
		(comment 1 "Grand Teton / footprints 5896-5897 of 9728")
	)
	(layers
		(0 "F.Cu" signal "TOP")
		(4 "In1.Cu" signal "GND")
		(6 "In2.Cu" signal "VCC")
		(8 "In3.Cu" signal "VCC1")
		(10 "In4.Cu" signal "GND1")
		(12 "In5.Cu" signal "IN1")
		(14 "In6.Cu" signal "GND2")
		(16 "In7.Cu" signal "IN2")
		(18 "In8.Cu" signal "GND3")
		(20 "In9.Cu" signal "IN3")
		(22 "In10.Cu" signal "GND4")
		(24 "In11.Cu" signal "IN4")
		(26 "In12.Cu" signal "GND5")
		(28 "In13.Cu" signal "IN5")
		(30 "In14.Cu" signal "GND6")
		(32 "In15.Cu" signal "IN6")
		(34 "In16.Cu" signal "GND7")
		(2 "B.Cu" signal "BOTTOM")
		(9 "F.Adhes" user "F.Adhesive")
		(11 "B.Adhes" user "B.Adhesive")
		(13 "F.Paste" user "Package Geometry/Pastemask Top")
		(15 "B.Paste" user "Package Geometry/Pastemask Bottom")
		(5 "F.SilkS" user "Ref Des/Silkscreen Top")
		(7 "B.SilkS" user "Ref Des/Silkscreen Bottom")
		(1 "F.Mask" user "Board Geometry/Soldermask Top")
		(3 "B.Mask" user "Board Geometry/Soldermask Bottom")
		(17 "Dwgs.User" user "User.Drawings")
		(19 "Cmts.User" user "User.Comments")
		(21 "Eco1.User" user "User.Eco1")
		(23 "Eco2.User" user "User.Eco2")
		(25 "Edge.Cuts" user "Board Geometry/Outline")
		(27 "Margin" user)
		(31 "F.CrtYd" user "Package Geometry/Place Bound Top")
		(29 "B.CrtYd" user "Package Geometry/Place Bound Bottom")
		(35 "F.Fab" user "Ref Des/Assembly Top")
		(33 "B.Fab" user "Ref Des/Assembly Bottom")
	)
	(footprint ""
		(layer "F.Cu")
		(at 413.264858 -26.785062 180)
		(property "Reference" "J44"
			(at 4.660392 -11.134344 90)
			(unlocked yes)
			(layer "F.SilkS")
			(effects
				(font
					(size 0.7874 0.5842)
					(thickness 0.1524)
				)
			)
		)
		(property "Value" ""
			(at 0 0 180)
			(layer "F.Fab")
			(effects
				(font
					(size 1.27 1.27)
				)
			)
		)
		(duplicate_pad_numbers_are_jumpers no)
		(fp_line
			(start 3.150108 12.115038)
			(end 1.529334 12.115038)
			(stroke
				(width 0.1524)
				(type default)
			)
			(layer "F.SilkS")
		)
		(fp_line
			(start 3.074924 12.014962)
			(end 1.632204 12.014962)
			(stroke
				(width 0.1524)
				(type default)
			)
			(layer "F.SilkS")
		)
		(fp_line
			(start 1.632204 -12.014962)
			(end 3.074924 -12.014962)
			(stroke
				(width 0.1524)
				(type default)
			)
			(layer "F.SilkS")
		)
		(fp_line
			(start 1.529334 -12.115038)
			(end 3.150108 -12.115038)
			(stroke
				(width 0.1524)
				(type default)
			)
			(layer "F.SilkS")
		)
		(fp_line
			(start -1.529334 12.115038)
			(end -3.150108 12.115038)
			(stroke
				(width 0.1524)
				(type default)
			)
			(layer "F.SilkS")
		)
		(fp_line
			(start -1.632204 12.014962)
			(end -3.074924 12.014962)
			(stroke
				(width 0.1524)
				(type default)
			)
			(layer "F.SilkS")
		)
		(fp_line
			(start -3.074924 -12.014962)
			(end -1.632204 -12.014962)
			(stroke
				(width 0.1524)
				(type default)
			)
			(layer "F.SilkS")
		)
		(fp_line
			(start -3.150108 -12.115038)
			(end -1.529334 -12.115038)
			(stroke
				(width 0.1524)
				(type default)
			)
			(layer "F.SilkS")
		)
		(fp_poly
			(pts
				(xy 3.620008 -8.68426) (xy 4.042664 -9.95172) (xy 4.887468 -9.106662)
			)
			(stroke
				(width 0)
				(type default)
			)
			(fill yes)
			(layer "F.SilkS")
		)
		(fp_line
			(start 3.074924 12.014962)
			(end -3.074924 12.014962)
			(stroke
				(width 0.1)
				(type default)
			)
			(layer "F.Fab")
		)
		(fp_line
			(start 3.074924 -12.014962)
			(end 3.074924 12.014962)
			(stroke
				(width 0.1)
				(type default)
			)
			(layer "F.Fab")
		)
		(fp_line
			(start -3.074924 12.014962)
			(end -3.074924 -12.014962)
			(stroke
				(width 0.1)
				(type default)
			)
			(layer "F.Fab")
		)
		(fp_line
			(start -3.074924 -12.014962)
			(end 3.074924 -12.014962)
			(stroke
				(width 0.1)
				(type default)
			)
			(layer "F.Fab")
		)
		(fp_poly
			(pts
				(xy 3.348736 -7.994904) (xy 4.543806 -8.592566) (xy 4.543806 -7.397496)
			)
			(stroke
				(width 0)
				(type default)
			)
			(fill yes)
			(layer "F.Fab")
		)
		(pad "" np_thru_hole circle
			(at -1.75006 -9.815068 90)
			(size 1.1176 1.1176)
			(drill 1.1176)
			(layers "*.Cu" "*.Mask")
			(clearance 0.381)
			(thermal_gap 0.381)
		)
		(pad "" np_thru_hole circle
			(at 0 9.815068 90)
			(size 1.1176 1.1176)
			(drill 1.1176)
			(layers "*.Cu" "*.Mask")
			(clearance 0.381)
			(thermal_gap 0.381)
		)
		(pad "A1" smd rect
			(at 2.29997 -7.994904 90)
			(size 0.381 1.27)
			(layers "F.Cu" "F.Mask" "F.Paste")
			(net "GND")
		)
		(pad "A2" smd rect
			(at 2.29997 -7.394956 90)
			(size 0.381 1.27)
			(layers "F.Cu" "F.Mask" "F.Paste")
			(net "GND")
		)
		(pad "A3" smd rect
			(at 2.29997 -6.795008 90)
			(size 0.381 1.27)
			(layers "F.Cu" "F.Mask" "F.Paste")
			(net "GND")
		)
		(pad "A4" smd rect
			(at 2.29997 -6.19506 90)
			(size 0.381 1.27)
			(layers "F.Cu" "F.Mask" "F.Paste")
			(net "GND")
		)
		(pad "A5" smd rect
			(at 2.29997 -5.595112 90)
			(size 0.381 1.27)
			(layers "F.Cu" "F.Mask" "F.Paste")
			(net "GND")
		)
		(pad "A6" smd rect
			(at 2.29997 -4.99491 90)
			(size 0.381 1.27)
			(layers "F.Cu" "F.Mask" "F.Paste")
			(net "GND")
		)
		(pad "A7" smd rect
			(at 2.29997 -4.394962 90)
			(size 0.381 1.27)
			(layers "F.Cu" "F.Mask" "F.Paste")
			(net "SMB_ISO_SSD14_R_SCL")
		)
		(pad "A8" smd rect
			(at 2.29997 -3.795014 90)
			(size 0.381 1.27)
			(layers "F.Cu" "F.Mask" "F.Paste")
			(net "SMB_ISO_SSD14_R_SDA")
		)
		(pad "A9" smd rect
			(at 2.29997 -3.195066 90)
			(size 0.381 1.27)
			(layers "F.Cu" "F.Mask" "F.Paste")
			(net "RST_SMB_SSD14_ISO_R_N")
		)
		(pad "A10" smd rect
			(at 2.29997 -2.595118 90)
			(size 0.381 1.27)
			(layers "F.Cu" "F.Mask" "F.Paste")
			(net "SSD14_LED_ISO_R_N")
		)
		(pad "A11" smd rect
			(at 2.29997 -1.994916 90)
			(size 0.381 1.27)
			(layers "F.Cu" "F.Mask" "F.Paste")
			(net "PU_CLKREQ14")
		)
		(pad "A12" smd rect
			(at 2.29997 -1.394968 90)
			(size 0.381 1.27)
			(layers "F.Cu" "F.Mask" "F.Paste")
			(net "PRSNT_SSD14_N")
		)
		(pad "A13" smd rect
			(at 2.29997 -0.79502 90)
			(size 0.381 1.27)
			(layers "F.Cu" "F.Mask" "F.Paste")
			(net "GND")
		)
		(pad "A14" smd rect
			(at 2.29997 -0.195072 90)
			(size 0.381 1.27)
			(layers "F.Cu" "F.Mask" "F.Paste")
			(net "Net_8465")
		)
		(pad "A15" smd rect
			(at 2.29997 0.404876 90)
			(size 0.381 1.27)
			(layers "F.Cu" "F.Mask" "F.Paste")
			(net "Net_8464")
		)
		(pad "A16" smd rect
			(at 2.29997 1.005078 90)
			(size 0.381 1.27)
			(layers "F.Cu" "F.Mask" "F.Paste")
			(net "GND")
		)
		(pad "A17" smd rect
			(at 2.29997 1.605026 90)
			(size 0.381 1.27)
			(layers "F.Cu" "F.Mask" "F.Paste")
			(net "P5E_PEX3_STN2_RX_DN<36>")
		)
		(pad "A18" smd rect
			(at 2.29997 2.204974 90)
			(size 0.381 1.27)
			(layers "F.Cu" "F.Mask" "F.Paste")
			(net "P5E_PEX3_STN2_RX_DP<36>")
		)
		(pad "A19" smd rect
			(at 2.29997 2.804922 90)
			(size 0.381 1.27)
			(layers "F.Cu" "F.Mask" "F.Paste")
			(net "GND")
		)
		(pad "A20" smd rect
			(at 2.29997 3.405124 90)
			(size 0.381 1.27)
			(layers "F.Cu" "F.Mask" "F.Paste")
			(net "P5E_PEX3_STN2_RX_DN<37>")
		)
		(pad "A21" smd rect
			(at 2.29997 4.005072 90)
			(size 0.381 1.27)
			(layers "F.Cu" "F.Mask" "F.Paste")
			(net "P5E_PEX3_STN2_RX_DP<37>")
		)
		(pad "A22" smd rect
			(at 2.29997 4.60502 90)
			(size 0.381 1.27)
			(layers "F.Cu" "F.Mask" "F.Paste")
			(net "GND")
		)
		(pad "A23" smd rect
			(at 2.29997 5.204968 90)
			(size 0.381 1.27)
			(layers "F.Cu" "F.Mask" "F.Paste")
			(net "P5E_PEX3_STN2_RX_DN<38>")
		)
		(pad "A24" smd rect
			(at 2.29997 5.804916 90)
			(size 0.381 1.27)
			(layers "F.Cu" "F.Mask" "F.Paste")
			(net "P5E_PEX3_STN2_RX_DP<38>")
		)
		(pad "A25" smd rect
			(at 2.29997 6.405118 90)
			(size 0.381 1.27)
			(layers "F.Cu" "F.Mask" "F.Paste")
			(net "GND")
		)
		(pad "A26" smd rect
			(at 2.29997 7.005066 90)
			(size 0.381 1.27)
			(layers "F.Cu" "F.Mask" "F.Paste")
			(net "P5E_PEX3_STN2_RX_DN<39>")
		)
		(pad "A27" smd rect
			(at 2.29997 7.605014 90)
			(size 0.381 1.27)
			(layers "F.Cu" "F.Mask" "F.Paste")
			(net "P5E_PEX3_STN2_RX_DP<39>")
		)
		(pad "A28" smd rect
			(at 2.29997 8.204962 90)
			(size 0.381 1.27)
			(layers "F.Cu" "F.Mask" "F.Paste")
			(net "GND")
		)
		(pad "B1" smd rect
			(at -2.29997 -7.994904 90)
			(size 0.381 1.27)
			(layers "F.Cu" "F.Mask" "F.Paste")
			(net "P12V_SSD14")
		)
		(pad "B2" smd rect
			(at -2.29997 -7.394956 90)
			(size 0.381 1.27)
			(layers "F.Cu" "F.Mask" "F.Paste")
			(net "P12V_SSD14")
		)
		(pad "B3" smd rect
			(at -2.29997 -6.795008 90)
			(size 0.381 1.27)
			(layers "F.Cu" "F.Mask" "F.Paste")
			(net "P12V_SSD14")
		)
		(pad "B4" smd rect
			(at -2.29997 -6.19506 90)
			(size 0.381 1.27)
			(layers "F.Cu" "F.Mask" "F.Paste")
			(net "P12V_SSD14")
		)
		(pad "B5" smd rect
			(at -2.29997 -5.595112 90)
			(size 0.381 1.27)
			(layers "F.Cu" "F.Mask" "F.Paste")
			(net "P12V_SSD14")
		)
		(pad "B6" smd rect
			(at -2.29997 -4.99491 90)
			(size 0.381 1.27)
			(layers "F.Cu" "F.Mask" "F.Paste")
			(net "P12V_SSD14")
		)
		(pad "B7" smd rect
			(at -2.29997 -4.394962 90)
			(size 0.381 1.27)
			(layers "F.Cu" "F.Mask" "F.Paste")
			(net "Net_8466")
		)
		(pad "B8" smd rect
			(at -2.29997 -3.795014 90)
			(size 0.381 1.27)
			(layers "F.Cu" "F.Mask" "F.Paste")
			(net "Net_8463")
		)
		(pad "B9" smd rect
			(at -2.29997 -3.195066 90)
			(size 0.381 1.27)
			(layers "F.Cu" "F.Mask" "F.Paste")
			(net "DUALPORT_N_SSD14")
		)
		(pad "B10" smd rect
			(at -2.29997 -2.595118 90)
			(size 0.381 1.27)
			(layers "F.Cu" "F.Mask" "F.Paste")
			(net "RST_SSD14_PERST_R_N")
		)
		(pad "B11" smd rect
			(at -2.29997 -1.994916 90)
			(size 0.381 1.27)
			(layers "F.Cu" "F.Mask" "F.Paste")
			(net "P3V3_SSD14")
		)
		(pad "B12" smd rect
			(at -2.29997 -1.394968 90)
			(size 0.381 1.27)
			(layers "F.Cu" "F.Mask" "F.Paste")
			(net "SSD14_PWRDIS_R")
		)
		(pad "B13" smd rect
			(at -2.29997 -0.79502 90)
			(size 0.381 1.27)
			(layers "F.Cu" "F.Mask" "F.Paste")
			(net "GND")
		)
		(pad "B14" smd rect
			(at -2.29997 -0.195072 90)
			(size 0.381 1.27)
			(layers "F.Cu" "F.Mask" "F.Paste")
			(net "CLK_100M_DB800ZL_SSD14_R_DN")
		)
		(pad "B15" smd rect
			(at -2.29997 0.404876 90)
			(size 0.381 1.27)
			(layers "F.Cu" "F.Mask" "F.Paste")
			(net "CLK_100M_DB800ZL_SSD14_R_DP")
		)
		(pad "B16" smd rect
			(at -2.29997 1.005078 90)
			(size 0.381 1.27)
			(layers "F.Cu" "F.Mask" "F.Paste")
			(net "GND")
		)
		(pad "B17" smd rect
			(at -2.29997 1.605026 90)
			(size 0.381 1.27)
			(layers "F.Cu" "F.Mask" "F.Paste")
			(net "P5E_PEX3_STN2_TX_C_DN<36>")
		)
		(pad "B18" smd rect
			(at -2.29997 2.204974 90)
			(size 0.381 1.27)
			(layers "F.Cu" "F.Mask" "F.Paste")
			(net "P5E_PEX3_STN2_TX_C_DP<36>")
		)
		(pad "B19" smd rect
			(at -2.29997 2.804922 90)
			(size 0.381 1.27)
			(layers "F.Cu" "F.Mask" "F.Paste")
			(net "GND")
		)
		(pad "B20" smd rect
			(at -2.29997 3.405124 90)
			(size 0.381 1.27)
			(layers "F.Cu" "F.Mask" "F.Paste")
			(net "P5E_PEX3_STN2_TX_C_DN<37>")
		)
		(pad "B21" smd rect
			(at -2.29997 4.005072 90)
			(size 0.381 1.27)
			(layers "F.Cu" "F.Mask" "F.Paste")
			(net "P5E_PEX3_STN2_TX_C_DP<37>")
		)
		(pad "B22" smd rect
			(at -2.29997 4.60502 90)
			(size 0.381 1.27)
			(layers "F.Cu" "F.Mask" "F.Paste")
			(net "GND")
		)
		(pad "B23" smd rect
			(at -2.29997 5.204968 90)
			(size 0.381 1.27)
			(layers "F.Cu" "F.Mask" "F.Paste")
			(net "P5E_PEX3_STN2_TX_C_DN<38>")
		)
		(pad "B24" smd rect
			(at -2.29997 5.804916 90)
			(size 0.381 1.27)
			(layers "F.Cu" "F.Mask" "F.Paste")
			(net "P5E_PEX3_STN2_TX_C_DP<38>")
		)
		(pad "B25" smd rect
			(at -2.29997 6.405118 90)
			(size 0.381 1.27)
			(layers "F.Cu" "F.Mask" "F.Paste")
			(net "GND")
		)
		(pad "B26" smd rect
			(at -2.29997 7.005066 90)
			(size 0.381 1.27)
			(layers "F.Cu" "F.Mask" "F.Paste")
			(net "P5E_PEX3_STN2_TX_C_DN<39>")
		)
		(pad "B27" smd rect
			(at -2.29997 7.605014 90)
			(size 0.381 1.27)
			(layers "F.Cu" "F.Mask" "F.Paste")
			(net "P5E_PEX3_STN2_TX_C_DP<39>")
		)
		(pad "B28" smd rect
			(at -2.29997 8.204962 90)
			(size 0.381 1.27)
			(layers "F.Cu" "F.Mask" "F.Paste")
			(net "GND")
		)
		(pad "G1" thru_hole oval
			(at 0 -11.364976 90)
			(size 1.6256 3.4798)
			(drill oval 1.1176 2.4638)
			(layers "*.Cu" "*.Mask")
			(remove_unused_layers no)
			(net "GND")
			(clearance 0.127)
			(thermal_gap 0.127)
		)
		(pad "G2" thru_hole oval
			(at 0 11.364976 90)
			(size 1.6256 3.4798)
			(drill oval 1.1176 2.4638)
			(layers "*.Cu" "*.Mask")
			(remove_unused_layers no)
			(net "GND")
			(clearance 0.127)
			(thermal_gap 0.127)
		)
		(zone
			(layer "F.Cu")
			(hatch none 0.5)
			(connect_pads
				(clearance 0)
			)
			(min_thickness 0.25)
			(keepout
				(tracks not_allowed)
				(vias allowed)
				(pads allowed)
				(copperpour not_allowed)
				(footprints allowed)
			)
			(placement
				(enabled no)
				(sheetname "")
			)
			(fill
				(thermal_gap 0.5)
				(thermal_bridge_width 0.5)
				(island_removal_mode 0)
			)
			(polygon
				(pts
					(xy 414.64484 -38.850062) (xy 411.894782 -38.850062) (xy 411.894782 -35.900106) (xy 414.64484 -35.900106)
				)
			)
		)
		(zone
			(layer "F.Cu")
			(hatch none 0.5)
			(connect_pads
				(clearance 0)
			)
			(min_thickness 0.25)
			(keepout
				(tracks not_allowed)
				(vias allowed)
				(pads allowed)
				(copperpour not_allowed)
				(footprints allowed)
			)
			(placement
				(enabled no)
				(sheetname "")
			)
			(fill
				(thermal_gap 0.5)
				(thermal_bridge_width 0.5)
				(island_removal_mode 0)
			)
			(polygon
				(pts
					(xy 415.714942 -17.670018) (xy 411.884876 -17.670018) (xy 411.884876 -14.720062) (xy 415.714942 -14.720062)
				)
			)
		)
		(zone
			(layers "F.Cu" "B.Cu" "In1.Cu" "In2.Cu" "In3.Cu" "In4.Cu" "In5.Cu" "In6.Cu"
				"In7.Cu" "In8.Cu" "In9.Cu" "In10.Cu" "In11.Cu" "In12.Cu" "In13.Cu" "In14.Cu"
				"In15.Cu" "In16.Cu"
			)
			(hatch none 0.5)
			(connect_pads
				(clearance 0)
			)
			(min_thickness 0.25)
			(keepout
				(tracks not_allowed)
				(vias allowed)
				(pads allowed)
				(copperpour not_allowed)
				(footprints allowed)
			)
			(placement
				(enabled no)
				(sheetname "")
			)
			(fill
				(thermal_gap 0.5)
				(thermal_bridge_width 0.5)
				(island_removal_mode 0)
			)
			(polygon
				(pts
					(arc
						(start 414.230058 -36.60013)
						(mid 412.299658 -36.60013)
						(end 414.230058 -36.60013)
					)
				)
			)
		)
		(zone
			(layers "F.Cu" "B.Cu" "In1.Cu" "In2.Cu" "In3.Cu" "In4.Cu" "In5.Cu" "In6.Cu"
				"In7.Cu" "In8.Cu" "In9.Cu" "In10.Cu" "In11.Cu" "In12.Cu" "In13.Cu" "In14.Cu"
				"In15.Cu" "In16.Cu"
			)
			(hatch none 0.5)
			(connect_pads
				(clearance 0)
			)
			(min_thickness 0.25)
			(keepout
				(tracks not_allowed)
				(vias allowed)
				(pads allowed)
				(copperpour not_allowed)
				(footprints allowed)
			)
			(placement
				(enabled no)
				(sheetname "")
			)
			(fill
				(thermal_gap 0.5)
				(thermal_bridge_width 0.5)
				(island_removal_mode 0)
			)
			(polygon
				(pts
					(arc
						(start 415.980118 -16.969994)
						(mid 414.049718 -16.969994)
						(end 415.980118 -16.969994)
					)
				)
			)
		)
	)
	(footprint ""
		(layer "F.Cu")
		(at 3.71983 -255.046734 -90)
		(property "Reference" "R6471"
			(at 0 0 270)
			(layer "F.SilkS")
			(hide yes)
			(effects
				(font
					(size 1.27 1.27)
				)
			)
		)
		(property "Value" ""
			(at 0 0 270)
			(layer "F.Fab")
			(effects
				(font
					(size 1.27 1.27)
				)
			)
		)
		(duplicate_pad_numbers_are_jumpers no)
		(fp_line
			(start -0.7874 0.4064)
			(end -0.7874 -0.4064)
			(stroke
				(width 0.1524)
				(type default)
			)
			(layer "F.SilkS")
		)
		(fp_line
			(start 0.7874 0.4064)
			(end -0.7874 0.4064)
			(stroke
				(width 0.1524)
				(type default)
			)
			(layer "F.SilkS")
		)
		(fp_line
			(start -0.7874 -0.4064)
			(end 0.7874 -0.4064)
			(stroke
				(width 0.1524)
				(type default)
			)
			(layer "F.SilkS")
		)
		(fp_line
			(start 0.7874 -0.4064)
			(end 0.7874 0.4064)
			(stroke
				(width 0.1524)
				(type default)
			)
			(layer "F.SilkS")
		)
		(fp_line
			(start -0.67945 0.3048)
			(end -0.67945 -0.305054)
			(stroke
				(width 0.1)
				(type default)
			)
			(layer "F.Fab")
		)
		(fp_line
			(start -0.12065 0.3048)
			(end -0.67945 0.3048)
			(stroke
				(width 0.1)
				(type default)
			)
			(layer "F.Fab")
		)
		(fp_line
			(start 0.120396 0.3048)
			(end 0.120396 0.2794)
			(stroke
				(width 0.1)
				(type default)
			)
			(layer "F.Fab")
		)
		(fp_line
			(start 0.67945 0.3048)
			(end 0.120396 0.3048)
			(stroke
				(width 0.1)
				(type default)
			)
			(layer "F.Fab")
		)
		(fp_line
			(start -0.12065 0.2794)
			(end -0.12065 0.3048)
			(stroke
				(width 0.1)
				(type default)
			)
			(layer "F.Fab")
		)
		(fp_line
			(start 0.120396 0.2794)
			(end -0.12065 0.2794)
			(stroke
				(width 0.1)
				(type default)
			)
			(layer "F.Fab")
		)
		(fp_line
			(start -0.12065 -0.2794)
			(end 0.12065 -0.2794)
			(stroke
				(width 0.1)
				(type default)
			)
			(layer "F.Fab")
		)
		(fp_line
			(start 0.12065 -0.2794)
			(end 0.12065 -0.3048)
			(stroke
				(width 0.1)
				(type default)
			)
			(layer "F.Fab")
		)
		(fp_line
			(start 0.12065 -0.3048)
			(end 0.67945 -0.3048)
			(stroke
				(width 0.1)
				(type default)
			)
			(layer "F.Fab")
		)
		(fp_line
			(start 0.67945 -0.3048)
			(end 0.67945 0.3048)
			(stroke
				(width 0.1)
				(type default)
			)
			(layer "F.Fab")
		)
		(fp_line
			(start -0.67945 -0.305054)
			(end -0.12065 -0.305054)
			(stroke
				(width 0.1)
				(type default)
			)
			(layer "F.Fab")
		)
		(fp_line
			(start -0.12065 -0.305054)
			(end -0.12065 -0.2794)
			(stroke
				(width 0.1)
				(type default)
			)
			(layer "F.Fab")
		)
		(pad "1" smd circle
			(at -0.40005 0 270)
			(size 0 0)
			(layers "F.Cu" "F.Mask" "F.Paste")
			(net "P1V25_SERDES_VDDPLL_PEX0")
		)
		(pad "2" smd circle
			(at 0.40005 0 270)
			(size 0 0)
			(layers "F.Cu" "F.Mask" "F.Paste")
			(net "P1V25_SERDES_VDDPLL_PEX0_C8")
		)
	)
)
